# T6G (Grand Teton) — schematic netlist excerpt (pin names and nets, part order shuffled) for the footprints in the layout excerpt that follows; sources: Cadence DE-HDL packaged netlist, KiCad conversion of 04192023_DAF0TMB3IC0_F0TG_MB_C_brd_V02_OCP.brd

C7014  Q_CAPP  470UF 2.5V 20% SPCAP  pkg SMLF  page 301 : A = P0V9_CPU0_RT2_2A ; B = GND

Q101  MOSFET_NCH_DUAL  PJT138K IC  pkg SOT363XD  page 126
  S1  = GND
  G1  = GPU_FPGA_THERM_OVERT_N
  D2  = GPU_FPGA_THERM_OVERT_ISO_N
  S2  = GND
  G2  = GPU_FPGA_THERM_OVERT
  D1  = GPU_FPGA_THERM_OVERT

(kicad_pcb
	(version 20260206)
	(generator "pcbnew")
	(generator_version "10.0")
	(general
		(thickness 1.6)
		(legacy_teardrops no)
	)
	(paper "A4")
	(title_block
		(title "04192023_DAF0TMB3IC0_F0TG_MB_C_brd_V02_OCP.brd")
		(comment 1 "Grand Teton / footprints 6539-6540 of 8354")
	)
	(layers
		(0 "F.Cu" signal "TOP")
		(4 "In1.Cu" signal "GND")
		(6 "In2.Cu" signal "IN1")
		(8 "In3.Cu" signal "GND1")
		(10 "In4.Cu" signal "IN2")
		(12 "In5.Cu" signal "GND2")
		(14 "In6.Cu" signal "IN3")
		(16 "In7.Cu" signal "GND3")
		(18 "In8.Cu" signal "VCC")
		(20 "In9.Cu" signal "VCC1")
		(22 "In10.Cu" signal "GND4")
		(24 "In11.Cu" signal "IN4")
		(26 "In12.Cu" signal "GND5")
		(28 "In13.Cu" signal "IN5")
		(30 "In14.Cu" signal "GND6")
		(32 "In15.Cu" signal "IN6")
		(34 "In16.Cu" signal "GND7")
		(2 "B.Cu" signal "BOTTOM")
		(9 "F.Adhes" user "F.Adhesive")
		(11 "B.Adhes" user "B.Adhesive")
		(13 "F.Paste" user "Package Geometry/Pastemask Top")
		(15 "B.Paste" user "Package Geometry/Pastemask Bottom")
		(5 "F.SilkS" user "Ref Des/Silkscreen Top")
		(7 "B.SilkS" user "Ref Des/Silkscreen Bottom")
		(1 "F.Mask" user "Board Geometry/Soldermask Top")
		(3 "B.Mask" user "Board Geometry/Soldermask Bottom")
		(17 "Dwgs.User" user "User.Drawings")
		(19 "Cmts.User" user "User.Comments")
		(21 "Eco1.User" user "User.Eco1")
		(23 "Eco2.User" user "User.Eco2")
		(25 "Edge.Cuts" user "Board Geometry/Outline")
		(27 "Margin" user)
		(31 "F.CrtYd" user "Package Geometry/Place Bound Top")
		(29 "B.CrtYd" user "Package Geometry/Place Bound Bottom")
		(35 "F.Fab" user "Ref Des/Assembly Top")
		(33 "B.Fab" user "Ref Des/Assembly Bottom")
	)
	(footprint ""
		(layer "B.Cu")
		(at 48.65624 -432.954938)
		(property "Reference" "Q101"
			(at -1.126998 -1.815846 0)
			(unlocked yes)
			(layer "B.SilkS")
			(effects
				(font
					(size 0.7874 0.5842)
					(thickness 0.1524)
				)
				(justify left mirror)
			)
		)
		(property "Value" ""
			(at 0 0 0)
			(layer "B.Fab")
			(effects
				(font
					(size 1.27 1.27)
				)
				(justify mirror)
			)
		)
		(duplicate_pad_numbers_are_jumpers no)
		(fp_line
			(start -1.332738 -1.100074)
			(end -1.332738 1.100074)
			(stroke
				(width 0.1524)
				(type default)
			)
			(layer "B.SilkS")
		)
		(fp_line
			(start -1.332738 1.100074)
			(end 1.332738 1.100074)
			(stroke
				(width 0.1524)
				(type default)
			)
			(layer "B.SilkS")
		)
		(fp_line
			(start -0.4826 -1.100074)
			(end -1.332738 -1.100074)
			(stroke
				(width 0.1524)
				(type default)
			)
			(layer "B.SilkS")
		)
		(fp_line
			(start 0 -0.541274)
			(end -0.4826 -1.100074)
			(stroke
				(width 0.1524)
				(type default)
			)
			(layer "B.SilkS")
		)
		(fp_line
			(start 0.4826 -1.100074)
			(end 0 -0.541274)
			(stroke
				(width 0.1524)
				(type default)
			)
			(layer "B.SilkS")
		)
		(fp_line
			(start 1.332738 -1.100074)
			(end 0.4826 -1.100074)
			(stroke
				(width 0.1524)
				(type default)
			)
			(layer "B.SilkS")
		)
		(fp_line
			(start 1.332738 1.100074)
			(end 1.332738 -1.100074)
			(stroke
				(width 0.1524)
				(type default)
			)
			(layer "B.SilkS")
		)
		(fp_poly
			(pts
				(xy 1.533144 -0.649986) (xy 2.2352 -0.298958) (xy 2.2352 -1.001014)
			)
			(stroke
				(width 0)
				(type default)
			)
			(fill yes)
			(layer "B.SilkS")
		)
		(fp_line
			(start -0.674878 -1.100074)
			(end -0.674878 1.100074)
			(stroke
				(width 0.1)
				(type default)
			)
			(layer "B.Fab")
		)
		(fp_line
			(start -0.674878 1.100074)
			(end 0.674878 1.100074)
			(stroke
				(width 0.1)
				(type default)
			)
			(layer "B.Fab")
		)
		(fp_line
			(start 0.674878 -1.100074)
			(end -0.674878 -1.100074)
			(stroke
				(width 0.1)
				(type default)
			)
			(layer "B.Fab")
		)
		(fp_line
			(start 0.674878 1.100074)
			(end 0.674878 -1.100074)
			(stroke
				(width 0.1)
				(type default)
			)
			(layer "B.Fab")
		)
		(fp_poly
			(pts
				(xy 2.2352 -0.298958) (xy 2.2352 -1.001014) (xy 1.533144 -0.649986)
			)
			(stroke
				(width 0)
				(type default)
			)
			(fill yes)
			(layer "B.Fab")
		)
		(pad "1" smd rect
			(at 0.94996 -0.649986 90)
			(size 0.4318 0.508)
			(layers "B.Cu" "B.Mask" "B.Paste")
			(net "GND")
		)
		(pad "2" smd rect
			(at 0.94996 0 90)
			(size 0.4318 0.508)
			(layers "B.Cu" "B.Mask" "B.Paste")
			(net "GPU_FPGA_THERM_OVERT_N")
		)
		(pad "3" smd rect
			(at 0.94996 0.649986 90)
			(size 0.4318 0.508)
			(layers "B.Cu" "B.Mask" "B.Paste")
			(net "GPU_FPGA_THERM_OVERT_ISO_N")
		)
		(pad "4" smd rect
			(at -0.94996 0.649986 90)
			(size 0.4318 0.508)
			(layers "B.Cu" "B.Mask" "B.Paste")
			(net "GND")
		)
		(pad "5" smd rect
			(at -0.94996 0 90)
			(size 0.4318 0.508)
			(layers "B.Cu" "B.Mask" "B.Paste")
			(net "GPU_FPGA_THERM_OVERT")
		)
		(pad "6" smd rect
			(at -0.94996 -0.649986 90)
			(size 0.4318 0.508)
			(layers "B.Cu" "B.Mask" "B.Paste")
			(net "GPU_FPGA_THERM_OVERT")
		)
	)
	(footprint ""
		(layer "B.Cu")
		(at 417.595558 -389.49503)
		(property "Reference" "C7014"
			(at 2.26314 2.989072 0)
			(unlocked yes)
			(layer "B.SilkS")
			(effects
				(font
					(size 0.7874 0.5842)
					(thickness 0.1524)
				)
				(justify left mirror)
			)
		)
		(property "Value" ""
			(at 0 0 0)
			(layer "B.Fab")
			(effects
				(font
					(size 1.27 1.27)
				)
				(justify mirror)
			)
		)
		(duplicate_pad_numbers_are_jumpers no)
		(fp_line
			(start -4.53898 -2.15011)
			(end -4.53898 2.15011)
			(stroke
				(width 0.1524)
				(type default)
			)
			(layer "B.SilkS")
		)
		(fp_line
			(start -4.53898 2.15011)
			(end 4.53898 2.15011)
			(stroke
				(width 0.1524)
				(type default)
			)
			(layer "B.SilkS")
		)
		(fp_line
			(start 4.53898 -2.150618)
			(end 4.539742 2.152142)
			(stroke
				(width 0.1524)
				(type default)
			)
			(layer "B.SilkS")
		)
		(fp_line
			(start 4.53898 -2.15011)
			(end -4.53898 -2.15011)
			(stroke
				(width 0.1524)
				(type default)
			)
			(layer "B.SilkS")
		)
		(fp_line
			(start 4.53898 2.15011)
			(end 4.53898 -2.15011)
			(stroke
				(width 0.1524)
				(type default)
			)
			(layer "B.SilkS")
		)
		(fp_line
			(start 4.69138 -2.150618)
			(end 4.692396 2.161032)
			(stroke
				(width 0.1524)
				(type default)
			)
			(layer "B.SilkS")
		)
		(fp_line
			(start 4.83108 2.150364)
			(end 4.447794 2.149348)
			(stroke
				(width 0.1524)
				(type default)
			)
			(layer "B.SilkS")
		)
		(fp_line
			(start 4.84378 -2.150618)
			(end 4.53898 -2.150618)
			(stroke
				(width 0.1524)
				(type default)
			)
			(layer "B.SilkS")
		)
		(fp_line
			(start 4.84378 -2.150618)
			(end 4.842256 2.163064)
			(stroke
				(width 0.1524)
				(type default)
			)
			(layer "B.SilkS")
		)
		(fp_line
			(start -3.64998 -2.15011)
			(end -3.64998 2.15011)
			(stroke
				(width 0.1)
				(type default)
			)
			(layer "B.Fab")
		)
		(fp_line
			(start -3.64998 2.15011)
			(end 3.64998 2.15011)
			(stroke
				(width 0.1)
				(type default)
			)
			(layer "B.Fab")
		)
		(fp_line
			(start 3.64998 -2.15011)
			(end -3.64998 -2.15011)
			(stroke
				(width 0.1)
				(type default)
			)
			(layer "B.Fab")
		)
		(fp_line
			(start 3.64998 2.15011)
			(end 3.64998 -2.15011)
			(stroke
				(width 0.1)
				(type default)
			)
			(layer "B.Fab")
		)
		(fp_text user "-"
			(at -2.944114 2.239772 0)
			(unlocked yes)
			(layer "B.SilkS")
			(effects
				(font
					(size 1.905 1.4224)
					(thickness 0.1524)
				)
				(justify left mirror)
			)
		)
		(fp_text user "+"
			(at 6.214872 -0.337058 0)
			(unlocked yes)
			(layer "B.SilkS")
			(effects
				(font
					(size 1.905 1.4224)
					(thickness 0.1524)
				)
				(justify left mirror)
			)
		)
		(fp_text user "-"
			(at -4.313174 -0.094488 0)
			(unlocked yes)
			(layer "B.Fab")
			(effects
				(font
					(size 1.905 1.4224)
					(thickness 0.1524)
				)
				(justify left mirror)
			)
		)
		(fp_text user "+"
			(at 6.214872 -0.337058 0)
			(unlocked yes)
			(layer "B.Fab")
			(effects
				(font
					(size 1.905 1.4224)
					(thickness 0.1524)
				)
				(justify left mirror)
			)
		)
		(pad "1" smd rect
			(at 3.199892 0 180)
			(size 2.413 2.8194)
			(layers "B.Cu" "B.Mask" "B.Paste")
			(net "P0V9_CPU0_RT2_2A")
		)
		(pad "2" smd rect
			(at -3.199892 0 180)
			(size 2.413 2.8194)
			(layers "B.Cu" "B.Mask" "B.Paste")
			(net "GND")
		)
	)
)
